# BASEBOARD_FAB2 (Tioga Pass) — schematic netlist excerpt (pin names and nets, part order shuffled) for the footprints in the layout excerpt that follows; sources: Cadence DE-HDL packaged netlist, KiCad conversion of Wiwynn_Tioga_Pass_MB.brd

C8P2  CAP  100UF 4V 20% X5R  pkg 0805  page 228 : A = PVDDQ_KLM ; B = GND
R1R16  RES  2.21K 1% CHIP  pkg 0402  page 188 : A = P3V3_STBY ; B = SMB_PCH_MEZZ_LOM2_SCL
C6U17  CAP_A  0.01UF 25V 10% X7R  pkg 0402V  page 48 : A = M_C_VREF ; B = GND

(kicad_pcb
	(version 20260206)
	(generator "pcbnew")
	(generator_version "10.0")
	(general
		(thickness 1.6)
		(legacy_teardrops no)
	)
	(paper "A4")
	(title_block
		(title "Wiwynn_Tioga_Pass_MB.brd")
		(comment 1 "Tioga Pass / footprints 4423-4425 of 4770")
	)
	(layers
		(0 "F.Cu" signal "TOP")
		(4 "In1.Cu" signal "L2GND")
		(6 "In2.Cu" signal "L3")
		(8 "In3.Cu" signal "L4GND")
		(10 "In4.Cu" signal "L5")
		(12 "In5.Cu" signal "L6GND")
		(14 "In6.Cu" signal "L7VCC")
		(16 "In7.Cu" signal "L8VCC")
		(18 "In8.Cu" signal "L9GND")
		(20 "In9.Cu" signal "L10")
		(22 "In10.Cu" signal "L11GND")
		(24 "In11.Cu" signal "L12")
		(26 "In12.Cu" signal "L13GND")
		(2 "B.Cu" signal "BOTTOM")
		(9 "F.Adhes" user "F.Adhesive")
		(11 "B.Adhes" user "B.Adhesive")
		(13 "F.Paste" user "Package Geometry/Pastemask Top")
		(15 "B.Paste" user "Package Geometry/Pastemask Bottom")
		(5 "F.SilkS" user "Ref Des/Silkscreen Top")
		(7 "B.SilkS" user "Ref Des/Silkscreen Bottom")
		(1 "F.Mask" user "Board Geometry/Soldermask Top")
		(3 "B.Mask" user "Board Geometry/Soldermask Bottom")
		(17 "Dwgs.User" user "User.Drawings")
		(19 "Cmts.User" user "User.Comments")
		(21 "Eco1.User" user "User.Eco1")
		(23 "Eco2.User" user "User.Eco2")
		(25 "Edge.Cuts" user "Board Geometry/Outline")
		(27 "Margin" user)
		(31 "F.CrtYd" user "Package Geometry/Place Bound Top")
		(29 "B.CrtYd" user "Package Geometry/Place Bound Bottom")
		(35 "F.Fab" user "Ref Des/Assembly Top")
		(33 "B.Fab" user "Ref Des/Assembly Bottom")
	)
	(footprint ""
		(layer "B.Cu")
		(at 100.672392 -85.075014)
		(property "Reference" "C8P2"
			(at 0 0 0)
			(layer "B.SilkS")
			(hide yes)
			(effects
				(font
					(size 1.27 1.27)
				)
				(justify mirror)
			)
		)
		(property "Value" ""
			(at 0 0 0)
			(layer "B.Fab")
			(effects
				(font
					(size 1.27 1.27)
				)
				(justify mirror)
			)
		)
		(duplicate_pad_numbers_are_jumpers no)
		(fp_poly
			(pts
				(xy 0.7239 -0.2159) (xy -0.7239 -0.2159) (xy -0.7239 1.9939) (xy 0.7239 1.9939)
			)
			(stroke
				(width 0)
				(type default)
			)
			(fill no)
			(layer "B.CrtYd")
		)
		(fp_line
			(start -0.7239 -0.2159)
			(end 0.7239 -0.2159)
			(stroke
				(width 0.1)
				(type default)
			)
			(layer "B.Fab")
		)
		(fp_line
			(start -0.7239 1.9939)
			(end -0.7239 -0.2159)
			(stroke
				(width 0.1)
				(type default)
			)
			(layer "B.Fab")
		)
		(fp_line
			(start 0.7239 -0.2159)
			(end 0.7239 1.9939)
			(stroke
				(width 0.1)
				(type default)
			)
			(layer "B.Fab")
		)
		(fp_line
			(start 0.7239 1.9939)
			(end -0.7239 1.9939)
			(stroke
				(width 0.1)
				(type default)
			)
			(layer "B.Fab")
		)
		(pad "1" smd rect
			(at 0 0 180)
			(size 1.27 1.016)
			(layers "B.Cu" "B.Mask" "B.Paste")
			(net "PVDDQ_KLM")
		)
		(pad "2" smd rect
			(at 0 1.778 180)
			(size 1.27 1.016)
			(layers "B.Cu" "B.Mask" "B.Paste")
			(net "GND")
		)
		(zone
			(layer "B.Cu")
			(hatch none 0.5)
			(connect_pads
				(clearance 0)
			)
			(min_thickness 0.25)
			(keepout
				(tracks not_allowed)
				(vias allowed)
				(pads allowed)
				(copperpour not_allowed)
				(footprints allowed)
			)
			(placement
				(enabled no)
				(sheetname "")
			)
			(fill
				(thermal_gap 0.5)
				(thermal_bridge_width 0.5)
				(island_removal_mode 0)
			)
			(polygon
				(pts
					(xy 101.307392 -84.567014) (xy 100.037392 -84.567014) (xy 100.037392 -83.805014) (xy 101.307392 -83.805014)
				)
			)
		)
	)
	(footprint ""
		(layer "B.Cu")
		(at 195.453 1.524 90)
		(property "Reference" "C6U17"
			(at 0 0 90)
			(layer "B.SilkS")
			(hide yes)
			(effects
				(font
					(size 1.27 1.27)
				)
				(justify mirror)
			)
		)
		(property "Value" ""
			(at 0 0 90)
			(layer "B.Fab")
			(effects
				(font
					(size 1.27 1.27)
				)
				(justify mirror)
			)
		)
		(duplicate_pad_numbers_are_jumpers no)
		(fp_poly
			(pts
				(xy -0.3048 -0.1016) (xy -0.3048 0.9906) (xy 0.3048 0.9906) (xy 0.3048 -0.1016)
			)
			(stroke
				(width 0)
				(type default)
			)
			(fill no)
			(layer "B.CrtYd")
		)
		(fp_line
			(start 0.3048 -0.1016)
			(end 0.3048 0.9906)
			(stroke
				(width 0.1)
				(type default)
			)
			(layer "B.Fab")
		)
		(fp_line
			(start -0.3048 -0.1016)
			(end 0.3048 -0.1016)
			(stroke
				(width 0.1)
				(type default)
			)
			(layer "B.Fab")
		)
		(fp_line
			(start 0.3048 0.9906)
			(end -0.3048 0.9906)
			(stroke
				(width 0.1)
				(type default)
			)
			(layer "B.Fab")
		)
		(fp_line
			(start -0.3048 0.9906)
			(end -0.3048 -0.1016)
			(stroke
				(width 0.1)
				(type default)
			)
			(layer "B.Fab")
		)
		(pad "1" smd rect
			(at 0 0 270)
			(size 0.508 0.508)
			(layers "B.Cu" "B.Mask" "B.Paste")
			(net "M_C_VREF")
		)
		(pad "2" smd rect
			(at 0 0.889 270)
			(size 0.508 0.508)
			(layers "B.Cu" "B.Mask" "B.Paste")
			(net "GND")
		)
		(zone
			(layer "B.Cu")
			(hatch none 0.5)
			(connect_pads
				(clearance 0)
			)
			(min_thickness 0.25)
			(keepout
				(tracks allowed)
				(vias not_allowed)
				(pads allowed)
				(copperpour not_allowed)
				(footprints allowed)
			)
			(placement
				(enabled no)
				(sheetname "")
			)
			(fill
				(thermal_gap 0.5)
				(thermal_bridge_width 0.5)
				(island_removal_mode 0)
			)
			(polygon
				(pts
					(xy 195.707 1.27) (xy 195.707 1.778) (xy 196.088 1.778) (xy 196.088 1.27)
				)
			)
		)
		(zone
			(layer "B.Cu")
			(hatch none 0.5)
			(connect_pads
				(clearance 0)
			)
			(min_thickness 0.25)
			(keepout
				(tracks not_allowed)
				(vias allowed)
				(pads allowed)
				(copperpour not_allowed)
				(footprints allowed)
			)
			(placement
				(enabled no)
				(sheetname "")
			)
			(fill
				(thermal_gap 0.5)
				(thermal_bridge_width 0.5)
				(island_removal_mode 0)
			)
			(polygon
				(pts
					(xy 196.088 1.27) (xy 196.088 1.778) (xy 195.707 1.778) (xy 195.707 1.27)
				)
			)
		)
	)
	(footprint ""
		(layer "B.Cu")
		(at 470.027 -62.484 -90)
		(property "Reference" "R1R16"
			(at 0 0 90)
			(layer "B.SilkS")
			(hide yes)
			(effects
				(font
					(size 1.27 1.27)
				)
				(justify mirror)
			)
		)
		(property "Value" ""
			(at 0 0 90)
			(layer "B.Fab")
			(effects
				(font
					(size 1.27 1.27)
				)
				(justify mirror)
			)
		)
		(duplicate_pad_numbers_are_jumpers no)
		(fp_poly
			(pts
				(xy 0.2794 -0.1016) (xy -0.2794 -0.1016) (xy -0.2794 0.9906) (xy 0.2794 0.9906)
			)
			(stroke
				(width 0)
				(type default)
			)
			(fill no)
			(layer "B.CrtYd")
		)
		(fp_line
			(start -0.2794 0.9906)
			(end -0.2794 -0.1016)
			(stroke
				(width 0.1)
				(type default)
			)
			(layer "B.Fab")
		)
		(fp_line
			(start 0.2794 0.9906)
			(end -0.2794 0.9906)
			(stroke
				(width 0.1)
				(type default)
			)
			(layer "B.Fab")
		)
		(fp_line
			(start -0.2794 -0.1016)
			(end 0.2794 -0.1016)
			(stroke
				(width 0.1)
				(type default)
			)
			(layer "B.Fab")
		)
		(fp_line
			(start 0.2794 -0.1016)
			(end 0.2794 0.9906)
			(stroke
				(width 0.1)
				(type default)
			)
			(layer "B.Fab")
		)
		(pad "1" smd rect
			(at 0 0 90)
			(size 0.508 0.508)
			(layers "B.Cu" "B.Mask" "B.Paste")
			(net "P3V3_STBY")
		)
		(pad "2" smd rect
			(at 0 0.889 90)
			(size 0.508 0.508)
			(layers "B.Cu" "B.Mask" "B.Paste")
			(net "SMB_PCH_MEZZ_LOM2_SCL")
		)
		(zone
			(layer "B.Cu")
			(hatch none 0.5)
			(connect_pads
				(clearance 0)
			)
			(min_thickness 0.25)
			(keepout
				(tracks not_allowed)
				(vias allowed)
				(pads allowed)
				(copperpour not_allowed)
				(footprints allowed)
			)
			(placement
				(enabled no)
				(sheetname "")
			)
			(fill
				(thermal_gap 0.5)
				(thermal_bridge_width 0.5)
				(island_removal_mode 0)
			)
			(polygon
				(pts
					(xy 469.392 -62.23) (xy 469.392 -62.738) (xy 469.773 -62.738) (xy 469.773 -62.23)
				)
			)
		)
		(zone
			(layer "B.Cu")
			(hatch none 0.5)
			(connect_pads
				(clearance 0)
			)
			(min_thickness 0.25)
			(keepout
				(tracks allowed)
				(vias not_allowed)
				(pads allowed)
				(copperpour not_allowed)
				(footprints allowed)
			)
			(placement
				(enabled no)
				(sheetname "")
			)
			(fill
				(thermal_gap 0.5)
				(thermal_bridge_width 0.5)
				(island_removal_mode 0)
			)
			(polygon
				(pts
					(xy 469.773 -62.23) (xy 469.773 -62.738) (xy 469.392 -62.738) (xy 469.392 -62.23)
				)
			)
		)
	)
)
